(kicad_pcb
	(version 20260206)
	(generator "pcbnew")
	(generator_version "10.0")
	(general
		(thickness 1.6)
		(legacy_teardrops no)
	)
	(paper "A4")
	(title_block
		(title "01162023_DA0F0TEBIF0_F0T_Expander_BD_F_brd_V02_OCP.brd")
		(comment 1 "Grand Teton / footprints 6609-6617 of 9728")
	)
	(layers
		(0 "F.Cu" signal "TOP")
		(4 "In1.Cu" signal "GND")
		(6 "In2.Cu" signal "VCC")
		(8 "In3.Cu" signal "VCC1")
		(10 "In4.Cu" signal "GND1")
		(12 "In5.Cu" signal "IN1")
		(14 "In6.Cu" signal "GND2")
		(16 "In7.Cu" signal "IN2")
		(18 "In8.Cu" signal "GND3")
		(20 "In9.Cu" signal "IN3")
		(22 "In10.Cu" signal "GND4")
		(24 "In11.Cu" signal "IN4")
		(26 "In12.Cu" signal "GND5")
		(28 "In13.Cu" signal "IN5")
		(30 "In14.Cu" signal "GND6")
		(32 "In15.Cu" signal "IN6")
		(34 "In16.Cu" signal "GND7")
		(2 "B.Cu" signal "BOTTOM")
		(9 "F.Adhes" user "F.Adhesive")
		(11 "B.Adhes" user "B.Adhesive")
		(13 "F.Paste" user "Package Geometry/Pastemask Top")
		(15 "B.Paste" user "Package Geometry/Pastemask Bottom")
		(5 "F.SilkS" user "Ref Des/Silkscreen Top")
		(7 "B.SilkS" user "Ref Des/Silkscreen Bottom")
		(1 "F.Mask" user "Board Geometry/Soldermask Top")
		(3 "B.Mask" user "Board Geometry/Soldermask Bottom")
		(17 "Dwgs.User" user "User.Drawings")
		(19 "Cmts.User" user "User.Comments")
		(21 "Eco1.User" user "User.Eco1")
		(23 "Eco2.User" user "User.Eco2")
		(25 "Edge.Cuts" user "Board Geometry/Outline")
		(27 "Margin" user)
		(31 "F.CrtYd" user "Package Geometry/Place Bound Top")
		(29 "B.CrtYd" user "Package Geometry/Place Bound Bottom")
		(35 "F.Fab" user "Ref Des/Assembly Top")
		(33 "B.Fab" user "Ref Des/Assembly Bottom")
	)
	(footprint ""
		(layer "F.Cu")
		(at 443.109096 -95.041466 -90)
		(property "Reference" "PC351"
			(at 0 0 270)
			(layer "F.SilkS")
			(hide yes)
			(effects
				(font
					(size 1.27 1.27)
				)
			)
		)
		(property "Value" ""
			(at 0 0 270)
			(layer "F.Fab")
			(effects
				(font
					(size 1.27 1.27)
				)
			)
		)
		(duplicate_pad_numbers_are_jumpers no)
		(fp_line
			(start -0.7874 0.4064)
			(end -0.7874 -0.4064)
			(stroke
				(width 0.1524)
				(type default)
			)
			(layer "F.SilkS")
		)
		(fp_line
			(start 0.7874 0.4064)
			(end -0.7874 0.4064)
			(stroke
				(width 0.1524)
				(type default)
			)
			(layer "F.SilkS")
		)
		(fp_line
			(start -0.7874 -0.4064)
			(end 0.7874 -0.4064)
			(stroke
				(width 0.1524)
				(type default)
			)
			(layer "F.SilkS")
		)
		(fp_line
			(start 0.7874 -0.4064)
			(end 0.7874 0.4064)
			(stroke
				(width 0.1524)
				(type default)
			)
			(layer "F.SilkS")
		)
		(fp_line
			(start -0.6858 0.3048)
			(end -0.6858 -0.3048)
			(stroke
				(width 0.1)
				(type default)
			)
			(layer "F.Fab")
		)
		(fp_line
			(start -0.1016 0.3048)
			(end -0.6858 0.3048)
			(stroke
				(width 0.1)
				(type default)
			)
			(layer "F.Fab")
		)
		(fp_line
			(start 0.1016 0.3048)
			(end 0.1016 0.2794)
			(stroke
				(width 0.1)
				(type default)
			)
			(layer "F.Fab")
		)
		(fp_line
			(start 0.6858 0.3048)
			(end 0.1016 0.3048)
			(stroke
				(width 0.1)
				(type default)
			)
			(layer "F.Fab")
		)
		(fp_line
			(start -0.1016 0.2794)
			(end -0.1016 0.3048)
			(stroke
				(width 0.1)
				(type default)
			)
			(layer "F.Fab")
		)
		(fp_line
			(start 0.1016 0.2794)
			(end -0.1016 0.2794)
			(stroke
				(width 0.1)
				(type default)
			)
			(layer "F.Fab")
		)
		(fp_line
			(start -0.1016 -0.2794)
			(end 0.1016 -0.2794)
			(stroke
				(width 0.1)
				(type default)
			)
			(layer "F.Fab")
		)
		(fp_line
			(start 0.1016 -0.2794)
			(end 0.1016 -0.3048)
			(stroke
				(width 0.1)
				(type default)
			)
			(layer "F.Fab")
		)
		(fp_line
			(start -0.6858 -0.3048)
			(end -0.1016 -0.3048)
			(stroke
				(width 0.1)
				(type default)
			)
			(layer "F.Fab")
		)
		(fp_line
			(start -0.1016 -0.3048)
			(end -0.1016 -0.2794)
			(stroke
				(width 0.1)
				(type default)
			)
			(layer "F.Fab")
		)
		(fp_line
			(start 0.1016 -0.3048)
			(end 0.6858 -0.3048)
			(stroke
				(width 0.1)
				(type default)
			)
			(layer "F.Fab")
		)
		(fp_line
			(start 0.6858 -0.3048)
			(end 0.6858 0.3048)
			(stroke
				(width 0.1)
				(type default)
			)
			(layer "F.Fab")
		)
		(pad "1" smd rect
			(at -0.40005 0 90)
			(size 0.4572 0.508)
			(layers "F.Cu" "F.Mask" "F.Paste")
			(net "P12V_NIC7_SS")
		)
		(pad "2" smd rect
			(at 0.40005 0 90)
			(size 0.4572 0.508)
			(layers "F.Cu" "F.Mask" "F.Paste")
			(net "GND")
		)
	)
	(footprint ""
		(layer "F.Cu")
		(at 258.54533 -208.019396)
		(property "Reference" "R2620"
			(at 0 0 0)
			(layer "F.SilkS")
			(hide yes)
			(effects
				(font
					(size 1.27 1.27)
				)
			)
		)
		(property "Value" ""
			(at 0 0 0)
			(layer "F.Fab")
			(effects
				(font
					(size 1.27 1.27)
				)
			)
		)
		(duplicate_pad_numbers_are_jumpers no)
		(fp_line
			(start -0.7874 -0.4064)
			(end 0.7874 -0.4064)
			(stroke
				(width 0.1524)
				(type default)
			)
			(layer "F.SilkS")
		)
		(fp_line
			(start -0.7874 0.4064)
			(end -0.7874 -0.4064)
			(stroke
				(width 0.1524)
				(type default)
			)
			(layer "F.SilkS")
		)
		(fp_line
			(start 0.7874 -0.4064)
			(end 0.7874 0.4064)
			(stroke
				(width 0.1524)
				(type default)
			)
			(layer "F.SilkS")
		)
		(fp_line
			(start 0.7874 0.4064)
			(end -0.7874 0.4064)
			(stroke
				(width 0.1524)
				(type default)
			)
			(layer "F.SilkS")
		)
		(fp_line
			(start -0.67945 -0.305054)
			(end -0.12065 -0.305054)
			(stroke
				(width 0.1)
				(type default)
			)
			(layer "F.Fab")
		)
		(fp_line
			(start -0.67945 0.3048)
			(end -0.67945 -0.305054)
			(stroke
				(width 0.1)
				(type default)
			)
			(layer "F.Fab")
		)
		(fp_line
			(start -0.12065 -0.305054)
			(end -0.12065 -0.2794)
			(stroke
				(width 0.1)
				(type default)
			)
			(layer "F.Fab")
		)
		(fp_line
			(start -0.12065 -0.2794)
			(end 0.12065 -0.2794)
			(stroke
				(width 0.1)
				(type default)
			)
			(layer "F.Fab")
		)
		(fp_line
			(start -0.12065 0.2794)
			(end -0.12065 0.3048)
			(stroke
				(width 0.1)
				(type default)
			)
			(layer "F.Fab")
		)
		(fp_line
			(start -0.12065 0.3048)
			(end -0.67945 0.3048)
			(stroke
				(width 0.1)
				(type default)
			)
			(layer "F.Fab")
		)
		(fp_line
			(start 0.120396 0.2794)
			(end -0.12065 0.2794)
			(stroke
				(width 0.1)
				(type default)
			)
			(layer "F.Fab")
		)
		(fp_line
			(start 0.120396 0.3048)
			(end 0.120396 0.2794)
			(stroke
				(width 0.1)
				(type default)
			)
			(layer "F.Fab")
		)
		(fp_line
			(start 0.12065 -0.3048)
			(end 0.67945 -0.3048)
			(stroke
				(width 0.1)
				(type default)
			)
			(layer "F.Fab")
		)
		(fp_line
			(start 0.12065 -0.2794)
			(end 0.12065 -0.3048)
			(stroke
				(width 0.1)
				(type default)
			)
			(layer "F.Fab")
		)
		(fp_line
			(start 0.67945 -0.3048)
			(end 0.67945 0.3048)
			(stroke
				(width 0.1)
				(type default)
			)
			(layer "F.Fab")
		)
		(fp_line
			(start 0.67945 0.3048)
			(end 0.120396 0.3048)
			(stroke
				(width 0.1)
				(type default)
			)
			(layer "F.Fab")
		)
		(pad "1" smd circle
			(at -0.40005 0)
			(size 0 0)
			(layers "F.Cu" "F.Mask" "F.Paste")
			(net "JTAG_FPGA_TDO")
		)
		(pad "2" smd circle
			(at 0.40005 0)
			(size 0 0)
			(layers "F.Cu" "F.Mask" "F.Paste")
			(net "P3V3_AUX")
		)
	)
	(footprint ""
		(layer "F.Cu")
		(at 71.588122 -356.244906 90)
		(property "Reference" "C118"
			(at 0 0 90)
			(layer "F.SilkS")
			(hide yes)
			(effects
				(font
					(size 1.27 1.27)
				)
			)
		)
		(property "Value" ""
			(at 0 0 90)
			(layer "F.Fab")
			(effects
				(font
					(size 1.27 1.27)
				)
			)
		)
		(duplicate_pad_numbers_are_jumpers no)
		(fp_line
			(start 0.299974 -0.150114)
			(end 0.299974 0.150114)
			(stroke
				(width 0.1)
				(type default)
			)
			(layer "F.Fab")
		)
		(fp_line
			(start -0.299974 -0.150114)
			(end 0.299974 -0.150114)
			(stroke
				(width 0.1)
				(type default)
			)
			(layer "F.Fab")
		)
		(fp_line
			(start 0.299974 0.150114)
			(end -0.299974 0.150114)
			(stroke
				(width 0.1)
				(type default)
			)
			(layer "F.Fab")
		)
		(fp_line
			(start -0.299974 0.150114)
			(end -0.299974 -0.150114)
			(stroke
				(width 0.1)
				(type default)
			)
			(layer "F.Fab")
		)
		(pad "1" smd rect
			(at -0.2667 0 90)
			(size 0.3048 0.381)
			(layers "F.Cu" "F.Mask" "F.Paste")
			(net "P5E_PEX0_STN5_TX_DN<85>")
		)
		(pad "2" smd rect
			(at 0.2667 0 90)
			(size 0.3048 0.381)
			(layers "F.Cu" "F.Mask" "F.Paste")
			(net "P5E_PEX0_STN5_TX_C_DN<85>")
		)
	)
	(footprint ""
		(layer "F.Cu")
		(at 72.446388 -58.323734)
		(property "Reference" "PC355"
			(at 0 0 0)
			(layer "F.SilkS")
			(hide yes)
			(effects
				(font
					(size 1.27 1.27)
				)
			)
		)
		(property "Value" ""
			(at 0 0 0)
			(layer "F.Fab")
			(effects
				(font
					(size 1.27 1.27)
				)
			)
		)
		(duplicate_pad_numbers_are_jumpers no)
		(fp_line
			(start -1.524 -0.762)
			(end 1.524 -0.762)
			(stroke
				(width 0.1524)
				(type default)
			)
			(layer "F.SilkS")
		)
		(fp_line
			(start -1.524 0.762)
			(end -1.524 -0.762)
			(stroke
				(width 0.1524)
				(type default)
			)
			(layer "F.SilkS")
		)
		(fp_line
			(start 1.524 -0.762)
			(end 1.524 0.762)
			(stroke
				(width 0.1524)
				(type default)
			)
			(layer "F.SilkS")
		)
		(fp_line
			(start 1.524 0.762)
			(end -1.524 0.762)
			(stroke
				(width 0.1524)
				(type default)
			)
			(layer "F.SilkS")
		)
		(fp_line
			(start -1.1049 -0.724916)
			(end -1.1049 0.724916)
			(stroke
				(width 0.1)
				(type default)
			)
			(layer "F.Fab")
		)
		(fp_line
			(start -1.1049 0.724916)
			(end 1.1049 0.724916)
			(stroke
				(width 0.1)
				(type default)
			)
			(layer "F.Fab")
		)
		(fp_line
			(start 1.1049 -0.724916)
			(end -1.1049 -0.724916)
			(stroke
				(width 0.1)
				(type default)
			)
			(layer "F.Fab")
		)
		(fp_line
			(start 1.1049 0.724916)
			(end 1.1049 -0.724916)
			(stroke
				(width 0.1)
				(type default)
			)
			(layer "F.Fab")
		)
		(pad "1" smd rect
			(at -0.889 0 180)
			(size 1.016 1.27)
			(layers "F.Cu" "F.Mask" "F.Paste")
			(net "GND")
		)
		(pad "2" smd rect
			(at 0.889 0 180)
			(size 1.016 1.27)
			(layers "F.Cu" "F.Mask" "F.Paste")
			(net "P12V_AUX")
		)
	)
	(footprint ""
		(layer "F.Cu")
		(at 384.938524 -109.20984)
		(property "Reference" "C687"
			(at 0 0 0)
			(layer "F.SilkS")
			(hide yes)
			(effects
				(font
					(size 1.27 1.27)
				)
			)
		)
		(property "Value" ""
			(at 0 0 0)
			(layer "F.Fab")
			(effects
				(font
					(size 1.27 1.27)
				)
			)
		)
		(duplicate_pad_numbers_are_jumpers no)
		(fp_line
			(start -0.299974 -0.150114)
			(end 0.299974 -0.150114)
			(stroke
				(width 0.1)
				(type default)
			)
			(layer "F.Fab")
		)
		(fp_line
			(start -0.299974 0.150114)
			(end -0.299974 -0.150114)
			(stroke
				(width 0.1)
				(type default)
			)
			(layer "F.Fab")
		)
		(fp_line
			(start 0.299974 -0.150114)
			(end 0.299974 0.150114)
			(stroke
				(width 0.1)
				(type default)
			)
			(layer "F.Fab")
		)
		(fp_line
			(start 0.299974 0.150114)
			(end -0.299974 0.150114)
			(stroke
				(width 0.1)
				(type default)
			)
			(layer "F.Fab")
		)
		(pad "1" smd rect
			(at -0.2667 0)
			(size 0.3048 0.381)
			(layers "F.Cu" "F.Mask" "F.Paste")
			(net "P5E_PEX3_STN1_TX_DP<21>")
		)
		(pad "2" smd rect
			(at 0.2667 0)
			(size 0.3048 0.381)
			(layers "F.Cu" "F.Mask" "F.Paste")
			(net "P5E_PEX3_STN1_TX_C_DP<21>")
		)
	)
	(footprint ""
		(layer "F.Cu")
		(at 250.81992 -15.649956 180)
		(property "Reference" "H111"
			(at -0.576834 2.852166 0)
			(unlocked yes)
			(layer "B.SilkS")
			(effects
				(font
					(size 0.7874 0.5842)
					(thickness 0.1524)
				)
				(justify left mirror)
			)
		)
		(property "Value" ""
			(at 0 0 180)
			(layer "F.Fab")
			(effects
				(font
					(size 1.27 1.27)
				)
			)
		)
		(duplicate_pad_numbers_are_jumpers no)
		(pad "1" thru_hole rect
			(at 0 0 180)
			(size 4.2164 5.0038)
			(drill 2.0066
				(offset 0.099822 0)
			)
			(layers "*.Cu" "*.Mask")
			(remove_unused_layers no)
			(net "Net_8552")
			(clearance -0.8509)
			(padstack
				(mode front_inner_back)
				(layer "Inner"
					(shape circle)
					(size 4.0132 4.0132)
					(clearance -0.7493)
				)
				(layer "B.Cu"
					(shape circle)
					(size 4.0132 4.0132)
					(clearance -0.7493)
				)
			)
		)
	)
	(footprint ""
		(layer "F.Cu")
		(at 105.019094 -397.512286 90)
		(property "Reference" "R5456"
			(at 0 0 90)
			(layer "F.SilkS")
			(hide yes)
			(effects
				(font
					(size 1.27 1.27)
				)
			)
		)
		(property "Value" ""
			(at 0 0 90)
			(layer "F.Fab")
			(effects
				(font
					(size 1.27 1.27)
				)
			)
		)
		(duplicate_pad_numbers_are_jumpers no)
		(fp_line
			(start 0.7874 -0.4064)
			(end 0.7874 0.4064)
			(stroke
				(width 0.1524)
				(type default)
			)
			(layer "F.SilkS")
		)
		(fp_line
			(start -0.7874 -0.4064)
			(end 0.7874 -0.4064)
			(stroke
				(width 0.1524)
				(type default)
			)
			(layer "F.SilkS")
		)
		(fp_line
			(start 0.7874 0.4064)
			(end -0.7874 0.4064)
			(stroke
				(width 0.1524)
				(type default)
			)
			(layer "F.SilkS")
		)
		(fp_line
			(start -0.7874 0.4064)
			(end -0.7874 -0.4064)
			(stroke
				(width 0.1524)
				(type default)
			)
			(layer "F.SilkS")
		)
		(fp_line
			(start -0.12065 -0.305054)
			(end -0.12065 -0.2794)
			(stroke
				(width 0.1)
				(type default)
			)
			(layer "F.Fab")
		)
		(fp_line
			(start -0.67945 -0.305054)
			(end -0.12065 -0.305054)
			(stroke
				(width 0.1)
				(type default)
			)
			(layer "F.Fab")
		)
		(fp_line
			(start 0.67945 -0.3048)
			(end 0.67945 0.3048)
			(stroke
				(width 0.1)
				(type default)
			)
			(layer "F.Fab")
		)
		(fp_line
			(start 0.12065 -0.3048)
			(end 0.67945 -0.3048)
			(stroke
				(width 0.1)
				(type default)
			)
			(layer "F.Fab")
		)
		(fp_line
			(start 0.12065 -0.2794)
			(end 0.12065 -0.3048)
			(stroke
				(width 0.1)
				(type default)
			)
			(layer "F.Fab")
		)
		(fp_line
			(start -0.12065 -0.2794)
			(end 0.12065 -0.2794)
			(stroke
				(width 0.1)
				(type default)
			)
			(layer "F.Fab")
		)
		(fp_line
			(start 0.120396 0.2794)
			(end -0.12065 0.2794)
			(stroke
				(width 0.1)
				(type default)
			)
			(layer "F.Fab")
		)
		(fp_line
			(start -0.12065 0.2794)
			(end -0.12065 0.3048)
			(stroke
				(width 0.1)
				(type default)
			)
			(layer "F.Fab")
		)
		(fp_line
			(start 0.67945 0.3048)
			(end 0.120396 0.3048)
			(stroke
				(width 0.1)
				(type default)
			)
			(layer "F.Fab")
		)
		(fp_line
			(start 0.120396 0.3048)
			(end 0.120396 0.2794)
			(stroke
				(width 0.1)
				(type default)
			)
			(layer "F.Fab")
		)
		(fp_line
			(start -0.12065 0.3048)
			(end -0.67945 0.3048)
			(stroke
				(width 0.1)
				(type default)
			)
			(layer "F.Fab")
		)
		(fp_line
			(start -0.67945 0.3048)
			(end -0.67945 -0.305054)
			(stroke
				(width 0.1)
				(type default)
			)
			(layer "F.Fab")
		)
		(pad "1" smd circle
			(at -0.40005 0 90)
			(size 0 0)
			(layers "F.Cu" "F.Mask" "F.Paste")
			(net "RST_BIC_USB_HUB_R1_N")
		)
		(pad "2" smd circle
			(at 0.40005 0 90)
			(size 0 0)
			(layers "F.Cu" "F.Mask" "F.Paste")
			(net "GND")
		)
	)
	(footprint ""
		(layer "F.Cu")
		(at 220.631512 -231.416606 90)
		(property "Reference" "R4546"
			(at 0 0 90)
			(layer "F.SilkS")
			(hide yes)
			(effects
				(font
					(size 1.27 1.27)
				)
			)
		)
		(property "Value" ""
			(at 0 0 90)
			(layer "F.Fab")
			(effects
				(font
					(size 1.27 1.27)
				)
			)
		)
		(duplicate_pad_numbers_are_jumpers no)
		(fp_line
			(start 0.7874 -0.4064)
			(end 0.7874 0.4064)
			(stroke
				(width 0.1524)
				(type default)
			)
			(layer "F.SilkS")
		)
		(fp_line
			(start -0.7874 -0.4064)
			(end 0.7874 -0.4064)
			(stroke
				(width 0.1524)
				(type default)
			)
			(layer "F.SilkS")
		)
		(fp_line
			(start 0.7874 0.4064)
			(end -0.7874 0.4064)
			(stroke
				(width 0.1524)
				(type default)
			)
			(layer "F.SilkS")
		)
		(fp_line
			(start -0.7874 0.4064)
			(end -0.7874 -0.4064)
			(stroke
				(width 0.1524)
				(type default)
			)
			(layer "F.SilkS")
		)
		(fp_line
			(start -0.12065 -0.305054)
			(end -0.12065 -0.2794)
			(stroke
				(width 0.1)
				(type default)
			)
			(layer "F.Fab")
		)
		(fp_line
			(start -0.67945 -0.305054)
			(end -0.12065 -0.305054)
			(stroke
				(width 0.1)
				(type default)
			)
			(layer "F.Fab")
		)
		(fp_line
			(start 0.67945 -0.3048)
			(end 0.67945 0.3048)
			(stroke
				(width 0.1)
				(type default)
			)
			(layer "F.Fab")
		)
		(fp_line
			(start 0.12065 -0.3048)
			(end 0.67945 -0.3048)
			(stroke
				(width 0.1)
				(type default)
			)
			(layer "F.Fab")
		)
		(fp_line
			(start 0.12065 -0.2794)
			(end 0.12065 -0.3048)
			(stroke
				(width 0.1)
				(type default)
			)
			(layer "F.Fab")
		)
		(fp_line
			(start -0.12065 -0.2794)
			(end 0.12065 -0.2794)
			(stroke
				(width 0.1)
				(type default)
			)
			(layer "F.Fab")
		)
		(fp_line
			(start 0.120396 0.2794)
			(end -0.12065 0.2794)
			(stroke
				(width 0.1)
				(type default)
			)
			(layer "F.Fab")
		)
		(fp_line
			(start -0.12065 0.2794)
			(end -0.12065 0.3048)
			(stroke
				(width 0.1)
				(type default)
			)
			(layer "F.Fab")
		)
		(fp_line
			(start 0.67945 0.3048)
			(end 0.120396 0.3048)
			(stroke
				(width 0.1)
				(type default)
			)
			(layer "F.Fab")
		)
		(fp_line
			(start 0.120396 0.3048)
			(end 0.120396 0.2794)
			(stroke
				(width 0.1)
				(type default)
			)
			(layer "F.Fab")
		)
		(fp_line
			(start -0.12065 0.3048)
			(end -0.67945 0.3048)
			(stroke
				(width 0.1)
				(type default)
			)
			(layer "F.Fab")
		)
		(fp_line
			(start -0.67945 0.3048)
			(end -0.67945 -0.305054)
			(stroke
				(width 0.1)
				(type default)
			)
			(layer "F.Fab")
		)
		(pad "1" smd circle
			(at -0.40005 0 90)
			(size 0 0)
			(layers "F.Cu" "F.Mask" "F.Paste")
			(net "REV_ID2")
		)
		(pad "2" smd circle
			(at 0.40005 0 90)
			(size 0 0)
			(layers "F.Cu" "F.Mask" "F.Paste")
			(net "P3V3_AUX")
		)
	)
	(footprint ""
		(layer "F.Cu")
		(at 20.221448 -350.098614 90)
		(property "Reference" "C192"
			(at 0 0 90)
			(layer "F.SilkS")
			(hide yes)
			(effects
				(font
					(size 1.27 1.27)
				)
			)
		)
		(property "Value" ""
			(at 0 0 90)
			(layer "F.Fab")
			(effects
				(font
					(size 1.27 1.27)
				)
			)
		)
		(duplicate_pad_numbers_are_jumpers no)
		(fp_line
			(start 0.299974 -0.150114)
			(end 0.299974 0.150114)
			(stroke
				(width 0.1)
				(type default)
			)
			(layer "F.Fab")
		)
		(fp_line
			(start -0.299974 -0.150114)
			(end 0.299974 -0.150114)
			(stroke
				(width 0.1)
				(type default)
			)
			(layer "F.Fab")
		)
		(fp_line
			(start 0.299974 0.150114)
			(end -0.299974 0.150114)
			(stroke
				(width 0.1)
				(type default)
			)
			(layer "F.Fab")
		)
		(fp_line
			(start -0.299974 0.150114)
			(end -0.299974 -0.150114)
			(stroke
				(width 0.1)
				(type default)
			)
			(layer "F.Fab")
		)
		(pad "1" smd rect
			(at -0.2667 0 90)
			(size 0.3048 0.381)
			(layers "F.Cu" "F.Mask" "F.Paste")
			(net "P5E_PEX0_STN7_TX_DN<112>")
		)
		(pad "2" smd rect
			(at 0.2667 0 90)
			(size 0.3048 0.381)
			(layers "F.Cu" "F.Mask" "F.Paste")
			(net "P5E_PEX0_STN7_TX_C_DN<112>")
		)
	)
)
